# BASEBOARD_FAB2 (Tioga Pass) — schematic netlist excerpt (pin names and nets, part order shuffled) for the footprints in the layout excerpt that follows; sources: Cadence DE-HDL packaged netlist, KiCad conversion of Wiwynn_Tioga_Pass_MB.brd

C6P23  CAPP  470UF 2.5V 20% ALUM  pkg 3018  page 203 : A = PVCCIN_CPU0 ; B = GND
R2R8  887R2F-L-GP  1%  pkg SMD-RG  page 187 : \1\ = FM_MEZZB_PRSNT1_N ; \2\ = GND
C4D6  SC1U10V2KX-4-GP  10%  pkg SMD-BCG6  page 203 : \1\ = P5V_STBY ; \2\ = GND

(kicad_pcb
	(version 20260206)
	(generator "pcbnew")
	(generator_version "10.0")
	(general
		(thickness 1.6)
		(legacy_teardrops no)
	)
	(paper "A4")
	(title_block
		(title "Wiwynn_Tioga_Pass_MB.brd")
		(comment 1 "Tioga Pass / footprints 4648-4650 of 4770")
	)
	(layers
		(0 "F.Cu" signal "TOP")
		(4 "In1.Cu" signal "L2GND")
		(6 "In2.Cu" signal "L3")
		(8 "In3.Cu" signal "L4GND")
		(10 "In4.Cu" signal "L5")
		(12 "In5.Cu" signal "L6GND")
		(14 "In6.Cu" signal "L7VCC")
		(16 "In7.Cu" signal "L8VCC")
		(18 "In8.Cu" signal "L9GND")
		(20 "In9.Cu" signal "L10")
		(22 "In10.Cu" signal "L11GND")
		(24 "In11.Cu" signal "L12")
		(26 "In12.Cu" signal "L13GND")
		(2 "B.Cu" signal "BOTTOM")
		(9 "F.Adhes" user "F.Adhesive")
		(11 "B.Adhes" user "B.Adhesive")
		(13 "F.Paste" user "Package Geometry/Pastemask Top")
		(15 "B.Paste" user "Package Geometry/Pastemask Bottom")
		(5 "F.SilkS" user "Ref Des/Silkscreen Top")
		(7 "B.SilkS" user "Ref Des/Silkscreen Bottom")
		(1 "F.Mask" user "Board Geometry/Soldermask Top")
		(3 "B.Mask" user "Board Geometry/Soldermask Bottom")
		(17 "Dwgs.User" user "User.Drawings")
		(19 "Cmts.User" user "User.Comments")
		(21 "Eco1.User" user "User.Eco1")
		(23 "Eco2.User" user "User.Eco2")
		(25 "Edge.Cuts" user "Board Geometry/Outline")
		(27 "Margin" user)
		(31 "F.CrtYd" user "Package Geometry/Place Bound Top")
		(29 "B.CrtYd" user "Package Geometry/Place Bound Bottom")
		(35 "F.Fab" user "Ref Des/Assembly Top")
		(33 "B.Fab" user "Ref Des/Assembly Bottom")
	)
	(footprint ""
		(layer "B.Cu")
		(at 437.7944 -50.4698 90)
		(property "Reference" "R2R8"
			(at 0 0 90)
			(layer "B.SilkS")
			(hide yes)
			(effects
				(font
					(size 1.27 1.27)
				)
				(justify mirror)
			)
		)
		(property "Value" "*"
			(at -0.064008 -4.108196 90)
			(unlocked yes)
			(layer "B.Fab")
			(hide yes)
			(effects
				(font
					(size 1.27 1.016)
					(thickness 0.1524)
				)
				(justify mirror)
			)
		)
		(property "Device Type" "887R2F-L-GP_SMD-RG-887R2F-L-GPA"
			(at -0.064008 -5.632196 90)
			(unlocked yes)
			(layer "B.Fab")
			(hide yes)
			(effects
				(font
					(size 1.27 1.016)
					(thickness 0.1524)
				)
				(justify mirror)
			)
		)
		(duplicate_pad_numbers_are_jumpers no)
		(fp_line
			(start 0.508 -0.9398)
			(end 0.508 0.9398)
			(stroke
				(width 0.1524)
				(type default)
			)
			(layer "B.SilkS")
		)
		(fp_line
			(start -0.508 -0.9398)
			(end 0.508 -0.9398)
			(stroke
				(width 0.1524)
				(type default)
			)
			(layer "B.SilkS")
		)
		(fp_rect
			(start 0.508 0.9398)
			(end -0.508 -0.9398)
			(stroke
				(width 0)
				(type default)
			)
			(fill no)
			(layer "B.CrtYd")
		)
		(fp_rect
			(start 0.508 0.9398)
			(end -0.508 -0.9398)
			(stroke
				(width 0)
				(type default)
			)
			(fill no)
			(layer "B.Fab")
		)
		(pad "1" smd custom
			(at 0 -0.4445 270)
			(size 0.1397 0.1397)
			(layers "B.Cu" "B.Mask" "B.Paste")
			(net "FM_MEZZB_PRSNT1_N")
			(options
				(clearance outline)
				(anchor circle)
			)
			(primitives
				(gr_poly
					(pts
						(arc
							(start -0.1778 0.2794)
							(mid -0.249642 0.249642)
							(end -0.2794 0.1778)
						)
						(arc
							(start -0.2794 -0.1778)
							(mid -0.249642 -0.249642)
							(end -0.1778 -0.2794)
						)
						(arc
							(start 0.1778 -0.2794)
							(mid 0.249642 -0.249642)
							(end 0.2794 -0.1778)
						)
						(arc
							(start 0.2794 0.1778)
							(mid 0.249642 0.249642)
							(end 0.1778 0.2794)
						)
					)
					(width 0)
					(fill yes)
				)
			)
		)
		(pad "2" smd custom
			(at 0 0.4445 270)
			(size 0.1397 0.1397)
			(layers "B.Cu" "B.Mask" "B.Paste")
			(net "GND")
			(options
				(clearance outline)
				(anchor circle)
			)
			(primitives
				(gr_poly
					(pts
						(arc
							(start -0.1778 0.2794)
							(mid -0.249642 0.249642)
							(end -0.2794 0.1778)
						)
						(arc
							(start -0.2794 -0.1778)
							(mid -0.249642 -0.249642)
							(end -0.1778 -0.2794)
						)
						(arc
							(start 0.1778 -0.2794)
							(mid 0.249642 -0.249642)
							(end 0.2794 -0.1778)
						)
						(arc
							(start 0.2794 0.1778)
							(mid 0.249642 0.249642)
							(end 0.1778 0.2794)
						)
					)
					(width 0)
					(fill yes)
				)
			)
		)
	)
	(footprint ""
		(layer "B.Cu")
		(at 198.803768 -77.613002 90)
		(property "Reference" "C4D6"
			(at 0 0 90)
			(layer "B.SilkS")
			(hide yes)
			(effects
				(font
					(size 1.27 1.27)
				)
				(justify mirror)
			)
		)
		(property "Value" "*"
			(at -1.1811 -2.8194 90)
			(unlocked yes)
			(layer "B.Fab")
			(hide yes)
			(effects
				(font
					(size 1.27 1.016)
					(thickness 0.1524)
				)
				(justify mirror)
			)
		)
		(property "Device Type" "SC1U10V2KX-4-GP_SMD-BCG6-SC1U1A"
			(at -1.1811 -4.3434 90)
			(unlocked yes)
			(layer "B.Fab")
			(hide yes)
			(effects
				(font
					(size 1.27 1.016)
					(thickness 0.1524)
				)
				(justify mirror)
			)
		)
		(duplicate_pad_numbers_are_jumpers no)
		(fp_rect
			(start 0.4318 0.9525)
			(end -0.4318 -0.9525)
			(stroke
				(width 0)
				(type default)
			)
			(fill no)
			(layer "B.CrtYd")
		)
		(fp_rect
			(start 0.4318 0.9525)
			(end -0.4318 -0.9525)
			(stroke
				(width 0)
				(type default)
			)
			(fill no)
			(layer "B.Fab")
		)
		(pad "1" smd custom
			(at 0 -0.4445 270)
			(size 0.1524 0.1524)
			(layers "B.Cu" "B.Mask" "B.Paste")
			(net "P5V_STBY")
			(options
				(clearance outline)
				(anchor circle)
			)
			(primitives
				(gr_poly
					(pts
						(arc
							(start 0.3048 0.2032)
							(mid 0.275042 0.275042)
							(end 0.2032 0.3048)
						)
						(arc
							(start -0.2032 0.3048)
							(mid -0.275042 0.275042)
							(end -0.3048 0.2032)
						)
						(arc
							(start -0.3048 -0.2032)
							(mid -0.275042 -0.275042)
							(end -0.2032 -0.3048)
						)
						(arc
							(start 0.2032 -0.3048)
							(mid 0.275042 -0.275042)
							(end 0.3048 -0.2032)
						)
					)
					(width 0)
					(fill yes)
				)
			)
		)
		(pad "2" smd custom
			(at 0 0.4445 270)
			(size 0.1524 0.1524)
			(layers "B.Cu" "B.Mask" "B.Paste")
			(net "GND")
			(options
				(clearance outline)
				(anchor circle)
			)
			(primitives
				(gr_poly
					(pts
						(arc
							(start 0.3048 0.2032)
							(mid 0.275042 0.275042)
							(end 0.2032 0.3048)
						)
						(arc
							(start -0.2032 0.3048)
							(mid -0.275042 0.275042)
							(end -0.3048 0.2032)
						)
						(arc
							(start -0.3048 -0.2032)
							(mid -0.275042 -0.275042)
							(end -0.2032 -0.3048)
						)
						(arc
							(start 0.2032 -0.3048)
							(mid 0.275042 -0.275042)
							(end 0.3048 -0.2032)
						)
					)
					(width 0)
					(fill yes)
				)
			)
		)
	)
	(footprint ""
		(layer "B.Cu")
		(at 210.847432 -67.945 -90)
		(property "Reference" "C6P23"
			(at 0.53467 -4.036568 0)
			(unlocked yes)
			(layer "B.SilkS")
			(effects
				(font
					(size 0.7874 0.5842)
					(thickness 0.1524)
				)
				(justify mirror)
			)
		)
		(property "Value" ""
			(at 0 0 90)
			(layer "B.Fab")
			(effects
				(font
					(size 1.27 1.27)
				)
				(justify mirror)
			)
		)
		(duplicate_pad_numbers_are_jumpers no)
		(fp_line
			(start -2.286 7.366)
			(end -1.600708 7.366)
			(stroke
				(width 0.1524)
				(type default)
			)
			(layer "B.SilkS")
		)
		(fp_line
			(start -2.286 7.366)
			(end -2.286 1.63195)
			(stroke
				(width 0.1524)
				(type default)
			)
			(layer "B.SilkS")
		)
		(fp_line
			(start 2.286 7.366)
			(end 1.60147 7.366)
			(stroke
				(width 0.1524)
				(type default)
			)
			(layer "B.SilkS")
		)
		(fp_line
			(start 2.286 7.366)
			(end 2.286 1.632712)
			(stroke
				(width 0.1524)
				(type default)
			)
			(layer "B.SilkS")
		)
		(fp_line
			(start -2.504948 1.633728)
			(end -1.6002 1.633728)
			(stroke
				(width 0.1524)
				(type default)
			)
			(layer "B.SilkS")
		)
		(fp_line
			(start 2.563114 1.633728)
			(end 1.6002 1.633728)
			(stroke
				(width 0.1524)
				(type default)
			)
			(layer "B.SilkS")
		)
		(fp_line
			(start -2.504948 -1.616456)
			(end -2.504948 1.633728)
			(stroke
				(width 0.1524)
				(type default)
			)
			(layer "B.SilkS")
		)
		(fp_line
			(start -1.6002 -1.616456)
			(end -2.504948 -1.616456)
			(stroke
				(width 0.1524)
				(type default)
			)
			(layer "B.SilkS")
		)
		(fp_line
			(start 1.6002 -1.616456)
			(end 2.563114 -1.616456)
			(stroke
				(width 0.1524)
				(type default)
			)
			(layer "B.SilkS")
		)
		(fp_line
			(start 2.563114 -1.616456)
			(end 2.563114 1.633728)
			(stroke
				(width 0.1524)
				(type default)
			)
			(layer "B.SilkS")
		)
		(fp_rect
			(start 2.286 7.366)
			(end -2.286 -0.254)
			(stroke
				(width 0)
				(type default)
			)
			(fill no)
			(layer "B.CrtYd")
		)
		(fp_line
			(start -2.286 7.366)
			(end 2.286 7.366)
			(stroke
				(width 0.1)
				(type default)
			)
			(layer "B.Fab")
		)
		(fp_line
			(start 2.286 7.366)
			(end 2.286 -0.254)
			(stroke
				(width 0.1)
				(type default)
			)
			(layer "B.Fab")
		)
		(fp_line
			(start -2.286 -0.254)
			(end -2.286 7.366)
			(stroke
				(width 0.1)
				(type default)
			)
			(layer "B.Fab")
		)
		(fp_line
			(start 2.286 -0.254)
			(end -2.286 -0.254)
			(stroke
				(width 0.1)
				(type default)
			)
			(layer "B.Fab")
		)
		(pad "1" smd rect
			(at 0 0 90)
			(size 2.54 3.048)
			(layers "B.Cu" "B.Mask" "B.Paste")
			(net "PVCCIN_CPU0")
		)
		(pad "2" smd rect
			(at 0 7.112 90)
			(size 2.54 3.048)
			(layers "B.Cu" "B.Mask" "B.Paste")
			(net "GND")
		)
	)
)
